FILE_TYPE = CONNECTIVITY;
{Allegro Design Entry HDL 16.6-p007 (v16-6-112F) 10/10/2012}
"PAGE_NUMBER" = 62;
0"NC";
1"M_M_DQS_DP<17:0>";
2"M_M_DQ<63:0>";
3"M_M_DQS_DN<17:0>";
4"M_M_MA<17:0>";
5"M_M_ECC<7:0>";
6"M_M_CLK_DP<3:0>";
7"M_M_CLK_DN<3:0>";
8"M_M_ODT<3:0>";
9"M_M_CS_N<7:0>";
10"M_M_CKE<3:0>";
11"M_M_BG<1:0>";
12"M_M_BA<1:0>";
13"M_M_DQ<55>";
14"M_M_DQ<41>";
15"M_M_DQ<53>";
16"M_M_ODT<3>";
17"M_M_DQ<35>";
18"M_M_DQ<38>";
19"M_M_DQS_DP<6>";
20"M_M_DQS_DP<5>";
21"M_M_DQS_DP<17>";
22"M_M_DQS_DP<16>";
23"M_M_DQS_DP<15>";
24"M_M_DQS_DP<9>";
25"M_M_DQS_DN<14>";
26"M_M_DQS_DN<13>";
27"M_M_DQS_DN<12>";
28"M_M_DQS_DN<11>";
29"M_M_DQS_DN<10>";
30"M_M_DQS_DN<9>";
31"M_M_DQS_DN<8>";
32"M_M_DQS_DN<7>";
33"M_M_DQS_DN<6>";
34"M_M_DQS_DN<3>";
35"M_M_DQS_DN<0>";
36"M_M_DQS_DP<3>";
37"M_M_DQS_DP<2>";
38"M_M_MA<17>";
39"M_M_MA<16>";
40"M_M_MA<15>";
41"M_M_MA<14>";
42"M_M_MA<13>";
43"M_M_MA<12>";
44"M_M_MA<11>";
45"M_M_MA<10>";
46"M_M_MA<9>";
47"M_M_MA<8>";
48"M_M_MA<3>";
49"M_M_ALERT_N";
50"M_M_ACT_N";
51"M_M_PAR";
52"M_M_BA<1>";
53"M_M_BA<0>";
54"M_M_BG<1>";
55"M_M_BG<0>";
56"M_M_CKE<3>";
57"M_M_CKE<2>";
58"M_M_CKE<1>";
59"M_M_CKE<0>";
60"M_M_CS_N<7>";
61"M_M_CS_N<6>";
62"M_M_CS_N<5>";
63"M_M_CS_N<4>";
64"M_M_CS_N<3>";
65"M_M_CS_N<2>";
66"M_M_CS_N<1>";
67"M_M_CS_N<0>";
68"M_M_MA<2>";
69"M_M_MA<1>";
70"M_M_MA<0>";
71"M_M_ODT<2>";
72"M_M_ODT<1>";
73"M_M_ODT<0>";
74"M_M_DQ<63>";
75"M_M_DQ<62>";
76"M_M_DQ<61>";
77"M_M_DQ<60>";
78"M_M_DQ<59>";
79"M_M_DQ<58>";
80"M_M_DQ<57>";
81"M_M_DQ<56>";
82"M_M_DQ<54>";
83"M_M_DQ<52>";
84"M_M_DQ<51>";
85"M_M_DQ<50>";
86"M_M_DQ<49>";
87"M_M_DQ<48>";
88"M_M_DQ<47>";
89"M_M_DQ<46>";
90"M_M_DQ<45>";
91"M_M_DQ<44>";
92"M_M_DQ<43>";
93"M_M_DQ<42>";
94"M_M_DQ<40>";
95"M_M_DQ<39>";
96"M_M_DQ<37>";
97"M_M_DQ<36>";
98"M_M_DQ<34>";
99"M_M_DQ<33>";
100"M_M_DQ<32>";
101"M_M_DQ<31>";
102"M_M_DQ<30>";
103"M_M_DQ<29>";
104"M_M_DQ<28>";
105"M_M_DQ<27>";
106"M_M_DQ<26>";
107"M_M_DQ<25>";
108"M_M_DQ<24>";
109"M_M_DQ<23>";
110"M_M_DQ<22>";
111"M_M_DQ<21>";
112"M_M_DQ<20>";
113"M_M_DQ<19>";
114"M_M_DQ<18>";
115"M_M_DQ<17>";
116"M_M_DQ<16>";
117"M_M_DQ<15>";
118"M_M_DQ<14>";
119"M_M_DQ<13>";
120"M_M_DQ<12>";
121"M_M_DQ<11>";
122"M_M_CLK_DN<3>";
123"M_M_CLK_DN<2>";
124"M_M_CLK_DN<1>";
125"M_M_CLK_DN<0>";
126"M_M_CLK_DP<3>";
127"M_M_CLK_DP<2>";
128"M_M_CLK_DP<1>";
129"M_M_CLK_DP<0>";
130"M_M_DQ<10>";
131"M_M_DQ<9>";
132"M_M_DQ<8>";
133"M_M_DQ<7>";
134"M_M_DQ<6>";
135"M_M_DQ<5>";
136"M_M_DQ<4>";
137"M_M_DQ<0>";
138"M_M_ECC<7>";
139"M_M_ECC<6>";
140"M_M_ECC<5>";
141"M_M_ECC<4>";
142"M_M_ECC<3>";
143"M_M_ECC<2>";
144"M_M_ECC<1>";
145"M_M_ECC<0>";
146"M_M_C<2>";
147"M_M_DQS_DP<10>";
148"M_M_DQS_DP<11>";
149"M_M_DQS_DP<12>";
150"M_M_DQS_DP<13>";
151"M_M_DQS_DP<14>";
152"M_M_MA<4>";
153"M_M_MA<5>";
154"M_M_MA<6>";
155"M_M_MA<7>";
156"M_M_DQS_DN<17>";
157"M_M_DQS_DP<0>";
158"M_M_DQS_DP<1>";
159"M_M_DQS_DN<16>";
160"M_M_DQS_DN<15>";
161"M_M_DQS_DN<1>";
162"M_M_DQS_DN<2>";
163"M_M_DQS_DN<5>";
164"M_M_DQS_DN<4>";
165"M_M_DQ<3>";
166"M_M_DQ<2>";
167"M_M_DQ<1>";
168"M_M_DQS_DP<4>";
169"M_M_DQS_DP<7>";
170"M_M_DQS_DP<8>";
%"TAP"
"6","(-5600,800)","0","mstr_standard","I10";
;
HDL_TAP"TRUE"
BODY_TYPE"PLUMBING"
CDS_LIB"mstr_standard";
"B \NAC \NWC"6;
"S \NAC"
BN"0"129;
%"TAP"
"6","(-2875,1550)","2","mstr_standard","I100";
;
HDL_TAP"TRUE"
BODY_TYPE"PLUMBING"
CDS_LIB"mstr_standard";
"B \NAC \NWC"8;
"S \NAC"
BN"3"16;
%"TAP"
"6","(-2875,1500)","2","mstr_standard","I101";
;
HDL_TAP"TRUE"
BODY_TYPE"PLUMBING"
CDS_LIB"mstr_standard";
"B \NAC \NWC"8;
"S \NAC"
BN"2"71;
%"TAP"
"6","(-2875,1450)","2","mstr_standard","I102";
;
HDL_TAP"TRUE"
BODY_TYPE"PLUMBING"
CDS_LIB"mstr_standard";
"B \NAC \NWC"8;
"S \NAC"
BN"1"72;
%"TAP"
"6","(-2875,1650)","2","mstr_standard","I103";
;
HDL_TAP"TRUE"
BODY_TYPE"PLUMBING"
CDS_LIB"mstr_standard";
"B \NAC \NWC"10;
"S \NAC"
BN"0"59;
%"TAP"
"6","(-2875,1700)","2","mstr_standard","I104";
;
HDL_TAP"TRUE"
BODY_TYPE"PLUMBING"
CDS_LIB"mstr_standard";
"B \NAC \NWC"10;
"S \NAC"
BN"1"58;
%"TAP"
"6","(-2875,1750)","2","mstr_standard","I105";
;
HDL_TAP"TRUE"
BODY_TYPE"PLUMBING"
CDS_LIB"mstr_standard";
"B \NAC \NWC"10;
"S \NAC"
BN"2"57;
%"TAP"
"6","(-2875,1800)","2","mstr_standard","I106";
;
HDL_TAP"TRUE"
BODY_TYPE"PLUMBING"
CDS_LIB"mstr_standard";
"B \NAC \NWC"10;
"S \NAC"
BN"3"56;
%"TAP"
"6","(-2875,1900)","2","mstr_standard","I107";
;
HDL_TAP"TRUE"
BODY_TYPE"PLUMBING"
CDS_LIB"mstr_standard";
"B \NAC \NWC"4;
"S \NAC"
BN"0"70;
%"TAP"
"6","(-2875,1950)","2","mstr_standard","I108";
;
HDL_TAP"TRUE"
BODY_TYPE"PLUMBING"
CDS_LIB"mstr_standard";
"B \NAC \NWC"4;
"S \NAC"
BN"1"69;
%"TAP"
"6","(-2875,2050)","2","mstr_standard","I109";
;
HDL_TAP"TRUE"
BODY_TYPE"PLUMBING"
CDS_LIB"mstr_standard";
"B \NAC \NWC"4;
"S \NAC"
BN"3"48;
%"TAP"
"6","(-5600,900)","0","mstr_standard","I11";
;
HDL_TAP"TRUE"
BODY_TYPE"PLUMBING"
CDS_LIB"mstr_standard";
"B \NAC \NWC"6;
"S \NAC"
BN"2"127;
%"TAP"
"6","(-2875,2000)","2","mstr_standard","I110";
;
HDL_TAP"TRUE"
BODY_TYPE"PLUMBING"
CDS_LIB"mstr_standard";
"B \NAC \NWC"4;
"S \NAC"
BN"2"68;
%"TAP"
"6","(-2875,2100)","2","mstr_standard","I111";
;
HDL_TAP"TRUE"
BODY_TYPE"PLUMBING"
CDS_LIB"mstr_standard";
"B \NAC \NWC"4;
"S \NAC"
BN"4"152;
%"TAP"
"6","(-2875,2150)","2","mstr_standard","I112";
;
HDL_TAP"TRUE"
BODY_TYPE"PLUMBING"
CDS_LIB"mstr_standard";
"B \NAC \NWC"4;
"S \NAC"
BN"5"153;
%"TAP"
"6","(-2875,2200)","2","mstr_standard","I113";
;
HDL_TAP"TRUE"
BODY_TYPE"PLUMBING"
CDS_LIB"mstr_standard";
"B \NAC \NWC"4;
"S \NAC"
BN"6"154;
%"TAP"
"6","(-2875,2300)","2","mstr_standard","I114";
;
HDL_TAP"TRUE"
BODY_TYPE"PLUMBING"
CDS_LIB"mstr_standard";
"B \NAC \NWC"4;
"S \NAC"
BN"8"47;
%"TAP"
"6","(-2875,2250)","2","mstr_standard","I115";
;
HDL_TAP"TRUE"
BODY_TYPE"PLUMBING"
CDS_LIB"mstr_standard";
"B \NAC \NWC"4;
"S \NAC"
BN"7"155;
%"TAP"
"6","(-2875,2450)","2","mstr_standard","I116";
;
HDL_TAP"TRUE"
BODY_TYPE"PLUMBING"
CDS_LIB"mstr_standard";
"B \NAC \NWC"4;
"S \NAC"
BN"11"44;
%"TAP"
"6","(-2875,2400)","2","mstr_standard","I117";
;
HDL_TAP"TRUE"
BODY_TYPE"PLUMBING"
CDS_LIB"mstr_standard";
"B \NAC \NWC"4;
"S \NAC"
BN"10"45;
%"TAP"
"6","(-2875,2350)","2","mstr_standard","I118";
;
HDL_TAP"TRUE"
BODY_TYPE"PLUMBING"
CDS_LIB"mstr_standard";
"B \NAC \NWC"4;
"S \NAC"
BN"9"46;
%"TAP"
"6","(-2875,2500)","2","mstr_standard","I119";
;
HDL_TAP"TRUE"
BODY_TYPE"PLUMBING"
CDS_LIB"mstr_standard";
"B \NAC \NWC"4;
"S \NAC"
BN"12"43;
%"TAP"
"6","(-5600,950)","0","mstr_standard","I12";
;
HDL_TAP"TRUE"
BODY_TYPE"PLUMBING"
CDS_LIB"mstr_standard";
"B \NAC \NWC"6;
"S \NAC"
BN"3"126;
%"TAP"
"6","(-2875,2550)","2","mstr_standard","I120";
;
HDL_TAP"TRUE"
BODY_TYPE"PLUMBING"
CDS_LIB"mstr_standard";
"B \NAC \NWC"4;
"S \NAC"
BN"13"42;
%"TAP"
"6","(-2875,2600)","2","mstr_standard","I121";
;
HDL_TAP"TRUE"
BODY_TYPE"PLUMBING"
CDS_LIB"mstr_standard";
"B \NAC \NWC"4;
"S \NAC"
BN"14"41;
%"TAP"
"6","(-2875,2650)","2","mstr_standard","I122";
;
HDL_TAP"TRUE"
BODY_TYPE"PLUMBING"
CDS_LIB"mstr_standard";
"B \NAC \NWC"4;
"S \NAC"
BN"15"40;
%"TAP"
"6","(-2875,2700)","2","mstr_standard","I123";
;
HDL_TAP"TRUE"
BODY_TYPE"PLUMBING"
CDS_LIB"mstr_standard";
"B \NAC \NWC"4;
"S \NAC"
BN"16"39;
%"TAP"
"6","(-2875,2750)","2","mstr_standard","I124";
;
HDL_TAP"TRUE"
BODY_TYPE"PLUMBING"
CDS_LIB"mstr_standard";
"B \NAC \NWC"4;
"S \NAC"
BN"17"38;
%"TAP"
"6","(-2875,2900)","2","mstr_standard","I125";
;
HDL_TAP"TRUE"
BODY_TYPE"PLUMBING"
CDS_LIB"mstr_standard";
"B \NAC \NWC"3;
"S \NAC"
BN"1"161;
%"TAP"
"6","(-2875,2950)","2","mstr_standard","I126";
;
HDL_TAP"TRUE"
BODY_TYPE"PLUMBING"
CDS_LIB"mstr_standard";
"B \NAC \NWC"3;
"S \NAC"
BN"2"162;
%"TAP"
"6","(-2875,2850)","2","mstr_standard","I127";
;
HDL_TAP"TRUE"
BODY_TYPE"PLUMBING"
CDS_LIB"mstr_standard";
"B \NAC \NWC"3;
"S \NAC"
BN"0"35;
%"TAP"
"6","(-2875,3050)","2","mstr_standard","I128";
;
HDL_TAP"TRUE"
BODY_TYPE"PLUMBING"
CDS_LIB"mstr_standard";
"B \NAC \NWC"3;
"S \NAC"
BN"4"164;
%"TAP"
"6","(-2875,3000)","2","mstr_standard","I129";
;
HDL_TAP"TRUE"
BODY_TYPE"PLUMBING"
CDS_LIB"mstr_standard";
"B \NAC \NWC"3;
"S \NAC"
BN"3"34;
%"TAP"
"6","(-5600,1050)","0","mstr_standard","I13";
;
HDL_TAP"TRUE"
BODY_TYPE"PLUMBING"
CDS_LIB"mstr_standard";
"B \NAC \NWC"5;
"S \NAC"
BN"0"145;
%"TAP"
"6","(-2875,3100)","2","mstr_standard","I130";
;
HDL_TAP"TRUE"
BODY_TYPE"PLUMBING"
CDS_LIB"mstr_standard";
"B \NAC \NWC"3;
"S \NAC"
BN"5"163;
%"TAP"
"6","(-2875,3150)","2","mstr_standard","I131";
;
HDL_TAP"TRUE"
BODY_TYPE"PLUMBING"
CDS_LIB"mstr_standard";
"B \NAC \NWC"3;
"S \NAC"
BN"6"33;
%"TAP"
"6","(-2875,3200)","2","mstr_standard","I132";
;
HDL_TAP"TRUE"
BODY_TYPE"PLUMBING"
CDS_LIB"mstr_standard";
"B \NAC \NWC"3;
"S \NAC"
BN"7"32;
%"TAP"
"6","(-2875,3250)","2","mstr_standard","I133";
;
HDL_TAP"TRUE"
BODY_TYPE"PLUMBING"
CDS_LIB"mstr_standard";
"B \NAC \NWC"3;
"S \NAC"
BN"8"31;
%"TAP"
"6","(-2875,3300)","2","mstr_standard","I134";
;
HDL_TAP"TRUE"
BODY_TYPE"PLUMBING"
CDS_LIB"mstr_standard";
"B \NAC \NWC"3;
"S \NAC"
BN"9"30;
%"TAP"
"6","(-2875,3350)","2","mstr_standard","I135";
;
HDL_TAP"TRUE"
BODY_TYPE"PLUMBING"
CDS_LIB"mstr_standard";
"B \NAC \NWC"3;
"S \NAC"
BN"10"29;
%"TAP"
"6","(-2875,3450)","2","mstr_standard","I136";
;
HDL_TAP"TRUE"
BODY_TYPE"PLUMBING"
CDS_LIB"mstr_standard";
"B \NAC \NWC"3;
"S \NAC"
BN"12"27;
%"TAP"
"6","(-2875,3400)","2","mstr_standard","I137";
;
HDL_TAP"TRUE"
BODY_TYPE"PLUMBING"
CDS_LIB"mstr_standard";
"B \NAC \NWC"3;
"S \NAC"
BN"11"28;
%"TAP"
"6","(-2875,3600)","2","mstr_standard","I138";
;
HDL_TAP"TRUE"
BODY_TYPE"PLUMBING"
CDS_LIB"mstr_standard";
"B \NAC \NWC"3;
"S \NAC"
BN"15"160;
%"TAP"
"6","(-2875,3550)","2","mstr_standard","I139";
;
HDL_TAP"TRUE"
BODY_TYPE"PLUMBING"
CDS_LIB"mstr_standard";
"B \NAC \NWC"3;
"S \NAC"
BN"14"25;
%"TAP"
"6","(-5600,1100)","0","mstr_standard","I14";
;
HDL_TAP"TRUE"
BODY_TYPE"PLUMBING"
CDS_LIB"mstr_standard";
"B \NAC \NWC"5;
"S \NAC"
BN"1"144;
%"TAP"
"6","(-2875,3500)","2","mstr_standard","I140";
;
HDL_TAP"TRUE"
BODY_TYPE"PLUMBING"
CDS_LIB"mstr_standard";
"B \NAC \NWC"3;
"S \NAC"
BN"13"26;
%"TAP"
"6","(-2875,3650)","2","mstr_standard","I141";
;
HDL_TAP"TRUE"
BODY_TYPE"PLUMBING"
CDS_LIB"mstr_standard";
"B \NAC \NWC"3;
"S \NAC"
BN"16"159;
%"TAP"
"6","(-2875,3700)","2","mstr_standard","I142";
;
HDL_TAP"TRUE"
BODY_TYPE"PLUMBING"
CDS_LIB"mstr_standard";
"B \NAC \NWC"3;
"S \NAC"
BN"17"156;
%"TAP"
"6","(-2875,3800)","2","mstr_standard","I143";
;
HDL_TAP"TRUE"
BODY_TYPE"PLUMBING"
CDS_LIB"mstr_standard";
"B \NAC \NWC"1;
"S \NAC"
BN"0"157;
%"TAP"
"6","(-2875,3850)","2","mstr_standard","I144";
;
HDL_TAP"TRUE"
BODY_TYPE"PLUMBING"
CDS_LIB"mstr_standard";
"B \NAC \NWC"1;
"S \NAC"
BN"1"158;
%"TAP"
"6","(-2875,3900)","2","mstr_standard","I145";
;
HDL_TAP"TRUE"
BODY_TYPE"PLUMBING"
CDS_LIB"mstr_standard";
"B \NAC \NWC"1;
"S \NAC"
BN"2"37;
%"TAP"
"6","(-2875,3950)","2","mstr_standard","I146";
;
HDL_TAP"TRUE"
BODY_TYPE"PLUMBING"
CDS_LIB"mstr_standard";
"B \NAC \NWC"1;
"S \NAC"
BN"3"36;
%"TAP"
"6","(-5600,1150)","0","mstr_standard","I15";
;
HDL_TAP"TRUE"
BODY_TYPE"PLUMBING"
CDS_LIB"mstr_standard";
"B \NAC \NWC"5;
"S \NAC"
BN"2"143;
%"TAP"
"6","(-2875,4000)","2","mstr_standard","I157";
;
HDL_TAP"TRUE"
BODY_TYPE"PLUMBING"
CDS_LIB"mstr_standard";
"B \NAC \NWC"1;
"S \NAC"
BN"4"168;
%"TAP"
"6","(-2875,4100)","2","mstr_standard","I158";
;
HDL_TAP"TRUE"
BODY_TYPE"PLUMBING"
CDS_LIB"mstr_standard";
"B \NAC \NWC"1;
"S \NAC"
BN"6"19;
%"TAP"
"6","(-2875,4050)","2","mstr_standard","I159";
;
HDL_TAP"TRUE"
BODY_TYPE"PLUMBING"
CDS_LIB"mstr_standard";
"B \NAC \NWC"1;
"S \NAC"
BN"5"20;
%"TAP"
"6","(-5600,1250)","0","mstr_standard","I16";
;
HDL_TAP"TRUE"
BODY_TYPE"PLUMBING"
CDS_LIB"mstr_standard";
"B \NAC \NWC"5;
"S \NAC"
BN"4"141;
%"TAP"
"6","(-2875,4150)","2","mstr_standard","I160";
;
HDL_TAP"TRUE"
BODY_TYPE"PLUMBING"
CDS_LIB"mstr_standard";
"B \NAC \NWC"1;
"S \NAC"
BN"7"169;
%"TAP"
"6","(-2875,4200)","2","mstr_standard","I161";
;
HDL_TAP"TRUE"
BODY_TYPE"PLUMBING"
CDS_LIB"mstr_standard";
"B \NAC \NWC"1;
"S \NAC"
BN"8"170;
%"TAP"
"6","(-2875,4250)","2","mstr_standard","I162";
;
HDL_TAP"TRUE"
BODY_TYPE"PLUMBING"
CDS_LIB"mstr_standard";
"B \NAC \NWC"1;
"S \NAC"
BN"9"24;
%"TAP"
"6","(-2875,4300)","2","mstr_standard","I163";
;
HDL_TAP"TRUE"
BODY_TYPE"PLUMBING"
CDS_LIB"mstr_standard";
"B \NAC \NWC"1;
"S \NAC"
BN"10"147;
%"TAP"
"6","(-2875,4350)","2","mstr_standard","I164";
;
HDL_TAP"TRUE"
BODY_TYPE"PLUMBING"
CDS_LIB"mstr_standard";
"B \NAC \NWC"1;
"S \NAC"
BN"11"148;
%"TAP"
"6","(-2875,4500)","2","mstr_standard","I165";
;
HDL_TAP"TRUE"
BODY_TYPE"PLUMBING"
CDS_LIB"mstr_standard";
"B \NAC \NWC"1;
"S \NAC"
BN"14"151;
%"TAP"
"6","(-2875,4450)","2","mstr_standard","I166";
;
HDL_TAP"TRUE"
BODY_TYPE"PLUMBING"
CDS_LIB"mstr_standard";
"B \NAC \NWC"1;
"S \NAC"
BN"13"150;
%"TAP"
"6","(-2875,4400)","2","mstr_standard","I167";
;
HDL_TAP"TRUE"
BODY_TYPE"PLUMBING"
CDS_LIB"mstr_standard";
"B \NAC \NWC"1;
"S \NAC"
BN"12"149;
%"TAP"
"6","(-2875,4550)","2","mstr_standard","I168";
;
HDL_TAP"TRUE"
BODY_TYPE"PLUMBING"
CDS_LIB"mstr_standard";
"B \NAC \NWC"1;
"S \NAC"
BN"15"23;
%"TAP"
"6","(-2875,4600)","2","mstr_standard","I169";
;
HDL_TAP"TRUE"
BODY_TYPE"PLUMBING"
CDS_LIB"mstr_standard";
"B \NAC \NWC"1;
"S \NAC"
BN"16"22;
%"TAP"
"6","(-5600,1200)","0","mstr_standard","I17";
;
HDL_TAP"TRUE"
BODY_TYPE"PLUMBING"
CDS_LIB"mstr_standard";
"B \NAC \NWC"5;
"S \NAC"
BN"3"142;
%"TAP"
"6","(-2875,4650)","2","mstr_standard","I170";
;
HDL_TAP"TRUE"
BODY_TYPE"PLUMBING"
CDS_LIB"mstr_standard";
"B \NAC \NWC"1;
"S \NAC"
BN"17"21;
%"SKX_EXT_B"
"8","(-4200,2550)","0","chpset_lib","I172";
;
CDS_SEC"8"
MATERIAL"IC"
PART_NUMBER"TBD"
LOCATION"U2D1"
CDS_LOCATION"U2D1"
SEC"8"
CDS_LIB"chpset_lib"
SEC_TYPE"BGA1"
PACK_TYPE"BGA1";
"DDR5_PAR"
$PN"DK53"51;
"DDR5_ODT<0>"
$PN"DG50"73;
"DDR5_ODT<1>"
$PN"DG48"72;
"DDR5_ODT<2>"
$PN"DK49"71;
"DDR5_ODT<3>"
$PN"DF47"16;
"DDR5_MA<0>"
$PN"DF53"70;
"DDR5_MA<1>"
$PN"DC58"69;
"DDR5_MA<2>"
$PN"DD57"68;
"DDR5_MA<3>"
$PN"DG58"48;
"DDR5_MA<4>"
$PN"DJ58"152;
"DDR5_MA<5>"
$PN"DF59"153;
"DDR5_MA<6>"
$PN"DK59"154;
"DDR5_MA<7>"
$PN"DC60"155;
"DDR5_MA<8>"
$PN"DD59"47;
"DDR5_MA<9>"
$PN"DA58"46;
"DDR5_MA<10>"
$PN"DD55"45;
"DDR5_MA<11>"
$PN"DA60"44;
"DDR5_MA<12>"
$PN"DG60"43;
"DDR5_MA<13>"
$PN"DD53"42;
"DDR5_MA<14>"
$PN"DJ50"41;
"DDR5_MA<15>"
$PN"DC54"40;
"DDR5_MA<16>"
$PN"DG52"39;
"DDR5_MA<17>"
$PN"DE46"38;
"DDR5_ECC<0>"
$PN"CH71"145;
"DDR5_ECC<1>"
$PN"CM71"144;
"DDR5_ECC<2>"
$PN"CJ68"143;
"DDR5_ECC<3>"
$PN"CL68"142;
"DDR5_ECC<4>"
$PN"CJ72"141;
"DDR5_ECC<5>"
$PN"CL72"140;
"DDR5_ECC<6>"
$PN"CH69"139;
"DDR5_ECC<7>"
$PN"CM69"138;
"DDR5_DQS_DP<0>"
$PN"CR76"157;
"DDR5_DQS_DP<1>"
$PN"DE76"158;
"DDR5_DQS_DP<2>"
$PN"DK71"37;
"DDR5_DQS_DP<3>"
$PN"CT65"36;
"DDR5_DQS_DP<4>"
$PN"DJ40"168;
"DDR5_DQS_DP<5>"
$PN"DJ32"20;
"DDR5_DQS_DP<6>"
$PN"DB35"19;
"DDR5_DQS_DP<7>"
$PN"DB29"169;
"DDR5_DQS_DP<8>"
$PN"CL70"170;
"DDR5_DQS_DP<9>"
$PN"CU74"24;
"DDR5_DQS_DP<10>"
$PN"DG74"147;
"DDR5_DQS_DP<11>"
$PN"DH69"148;
"DDR5_DQS_DP<12>"
$PN"CM65"149;
"DDR5_DQS_DP<13>"
$PN"DC40"150;
"DDR5_DQS_DP<14>"
$PN"DE32"151;
"DDR5_DQS_DP<15>"
$PN"CV35"23;
"DDR5_DQS_DP<16>"
$PN"CV29"22;
"DDR5_DQS_DP<17>"
$PN"CG70"21;
"DDR5_DQS_DN<0>"
$PN"CP77"35;
"DDR5_DQS_DN<1>"
$PN"DD77"161;
"DDR5_DQS_DN<2>"
$PN"DL72"162;
"DDR5_DQS_DN<3>"
$PN"CV65"34;
"DDR5_DQS_DN<4>"
$PN"DG40"164;
"DDR5_DQS_DN<5>"
$PN"DL32"163;
"DDR5_DQS_DN<6>"
$PN"DD35"33;
"DDR5_DQS_DN<7>"
$PN"DD29"32;
"DDR5_DQS_DN<8>"
$PN"CN70"31;
"DDR5_DQS_DN<9>"
$PN"CT75"30;
"DDR5_DQS_DN<10>"
$PN"DF75"29;
"DDR5_DQS_DN<11>"
$PN"DJ70"28;
"DDR5_DQS_DN<12>"
$PN"CP65"27;
"DDR5_DQS_DN<13>"
$PN"DE40"26;
"DDR5_DQS_DN<14>"
$PN"DG32"25;
"DDR5_DQS_DN<15>"
$PN"CY35"160;
"DDR5_DQS_DN<16>"
$PN"CY29"159;
"DDR5_DQS_DN<17>"
$PN"CJ70"156;
"DDR5_DQ<0>"
$PN"CR74"137;
"DDR5_DQ<1>"
$PN"CN76"167;
"DDR5_DQ<2>"
$PN"CW76"166;
"DDR5_DQ<3>"
$PN"CV77"165;
"DDR5_DQ<4>"
$PN"CN74"136;
"DDR5_DQ<5>"
$PN"CM75"135;
"DDR5_DQ<6>"
$PN"CV75"134;
"DDR5_DQ<7>"
$PN"CT77"133;
"DDR5_DQ<8>"
$PN"DE74"132;
"DDR5_DQ<9>"
$PN"DC76"131;
"DDR5_DQ<10>"
$PN"DH75"130;
"DDR5_DQ<11>"
$PN"DJ76"121;
"DDR5_DQ<12>"
$PN"DC74"120;
"DDR5_DQ<13>"
$PN"DB75"119;
"DDR5_DQ<14>"
$PN"DF77"118;
"DDR5_DQ<15>"
$PN"DH77"117;
"DDR5_DQ<16>"
$PN"DG70"116;
"DDR5_DQ<17>"
$PN"DJ72"115;
"DDR5_DQ<18>"
$PN"DM69"114;
"DDR5_DQ<19>"
$PN"DN70"113;
"DDR5_DQ<20>"
$PN"DF71"112;
"DDR5_DQ<21>"
$PN"DG72"111;
"DDR5_DQ<22>"
$PN"DK69"110;
"DDR5_DQ<23>"
$PN"DM71"109;
"DDR5_DQ<24>"
$PN"CN66"108;
"DDR5_DQ<25>"
$PN"CU66"107;
"DDR5_DQ<26>"
$PN"CP63"106;
"DDR5_DQ<27>"
$PN"CT63"105;
"DDR5_DQ<28>"
$PN"CP67"104;
"DDR5_DQ<29>"
$PN"CT67"103;
"DDR5_DQ<30>"
$PN"CN64"102;
"DDR5_DQ<31>"
$PN"CU64"101;
"DDR5_DQ<32>"
$PN"DD41"100;
"DDR5_DQ<33>"
$PN"DG42"99;
"DDR5_DQ<34>"
$PN"DE38"98;
"DDR5_DQ<35>"
$PN"DG38"17;
"DDR5_DQ<36>"
$PN"DA42"97;
"DDR5_DQ<37>"
$PN"DE42"96;
"DDR5_DQ<38>"
$PN"DD39"18;
"DDR5_DQ<39>"
$PN"DH39"95;
"DDR5_DQ<40>"
$PN"DF33"94;
"DDR5_DQ<41>"
$PN"DK33"14;
"DDR5_DQ<42>"
$PN"DG30"93;
"DDR5_DQ<43>"
$PN"DJ30"92;
"DDR5_DQ<44>"
$PN"DG34"91;
"DDR5_DQ<45>"
$PN"DJ34"90;
"DDR5_DQ<46>"
$PN"DF31"89;
"DDR5_DQ<47>"
$PN"DK31"88;
"DDR5_DQ<48>"
$PN"CW36"87;
"DDR5_DQ<49>"
$PN"DC36"86;
"DDR5_DQ<50>"
$PN"CY33"85;
"DDR5_DQ<51>"
$PN"DB33"84;
"DDR5_DQ<52>"
$PN"CY37"83;
"DDR5_DQ<53>"
$PN"DB37"15;
"DDR5_DQ<54>"
$PN"CW34"82;
"DDR5_DQ<55>"
$PN"DC34"13;
"DDR5_DQ<56>"
$PN"CW30"81;
"DDR5_DQ<57>"
$PN"DC30"80;
"DDR5_DQ<58>"
$PN"CY27"79;
"DDR5_DQ<59>"
$PN"DB27"78;
"DDR5_DQ<60>"
$PN"CY31"77;
"DDR5_DQ<61>"
$PN"DB31"76;
"DDR5_DQ<62>"
$PN"CW28"75;
"DDR5_DQ<63>"
$PN"DC28"74;
"DDR5_CS_N<0>"
$PN"DK51"67;
"DDR5_CS_N<1>"
$PN"DF49"66;
"DDR5_CS_N<2>"
$PN"DJ46"65;
"DDR5_CS_N<3>"
$PN"DG46"64;
"DDR5_CS_N<4>"
$PN"DF51"63;
"DDR5_CS_N<5>"
$PN"DJ48"62;
"DDR5_CS_N<6>"
$PN"DM45"61;
"DDR5_CS_N<7>"
$PN"DK45"60;
"DDR5_CLK_DP<0>"
$PN"DJ54"129;
"DDR5_CLK_DP<1>"
$PN"DG54"128;
"DDR5_CLK_DP<2>"
$PN"DJ56"127;
"DDR5_CLK_DP<3>"
$PN"DG56"126;
"DDR5_CLK_DN<0>"
$PN"DK55"125;
"DDR5_CLK_DN<1>"
$PN"DF55"124;
"DDR5_CLK_DN<2>"
$PN"DK57"123;
"DDR5_CLK_DN<3>"
$PN"DF57"122;
"DDR5_CKE<0>"
$PN"DG62"59;
"DDR5_CKE<1>"
$PN"DD63"58;
"DDR5_CKE<2>"
$PN"DK63"57;
"DDR5_CKE<3>"
$PN"DF63"56;
"DDR5_CID<2>"
$PN"DF45"146;
"DDR5_BG<0>"
$PN"DA62"55;
"DDR5_BG<1>"
$PN"DF61"54;
"DDR5_BA<0>"
$PN"DJ52"53;
"DDR5_BA<1>"
$PN"DC56"52;
"DDR5_ALERT_N"
$PN"DD61"49;
"DDR5_ACT_N"
$PN"DC62"50;
%"TAP"
"6","(-5600,1300)","0","mstr_standard","I18";
;
HDL_TAP"TRUE"
BODY_TYPE"PLUMBING"
CDS_LIB"mstr_standard";
"B \NAC \NWC"5;
"S \NAC"
BN"5"140;
%"TAP"
"6","(-5600,1350)","0","mstr_standard","I19";
;
HDL_TAP"TRUE"
BODY_TYPE"PLUMBING"
CDS_LIB"mstr_standard";
"B \NAC \NWC"5;
"S \NAC"
BN"6"139;
%"TAP"
"6","(-5600,1400)","0","mstr_standard","I20";
;
HDL_TAP"TRUE"
BODY_TYPE"PLUMBING"
CDS_LIB"mstr_standard";
"B \NAC \NWC"5;
"S \NAC"
BN"7"138;
%"TAP"
"6","(-5600,1500)","0","mstr_standard","I21";
;
HDL_TAP"TRUE"
BODY_TYPE"PLUMBING"
CDS_LIB"mstr_standard";
"B \NAC \NWC"2;
"S \NAC"
BN"0"137;
%"TAP"
"6","(-5600,1550)","0","mstr_standard","I22";
;
HDL_TAP"TRUE"
BODY_TYPE"PLUMBING"
CDS_LIB"mstr_standard";
"B \NAC \NWC"2;
"S \NAC"
BN"1"167;
%"TAP"
"6","(-5600,1600)","0","mstr_standard","I23";
;
HDL_TAP"TRUE"
BODY_TYPE"PLUMBING"
CDS_LIB"mstr_standard";
"B \NAC \NWC"2;
"S \NAC"
BN"2"166;
%"TAP"
"6","(-5600,1650)","0","mstr_standard","I24";
;
HDL_TAP"TRUE"
BODY_TYPE"PLUMBING"
CDS_LIB"mstr_standard";
"B \NAC \NWC"2;
"S \NAC"
BN"3"165;
%"TAP"
"6","(-5600,1700)","0","mstr_standard","I25";
;
HDL_TAP"TRUE"
BODY_TYPE"PLUMBING"
CDS_LIB"mstr_standard";
"B \NAC \NWC"2;
"S \NAC"
BN"4"136;
%"TAP"
"6","(-5600,1750)","0","mstr_standard","I26";
;
HDL_TAP"TRUE"
BODY_TYPE"PLUMBING"
CDS_LIB"mstr_standard";
"B \NAC \NWC"2;
"S \NAC"
BN"5"135;
%"TAP"
"6","(-5600,1800)","0","mstr_standard","I27";
;
HDL_TAP"TRUE"
BODY_TYPE"PLUMBING"
CDS_LIB"mstr_standard";
"B \NAC \NWC"2;
"S \NAC"
BN"6"134;
%"TAP"
"6","(-5600,1900)","0","mstr_standard","I28";
;
HDL_TAP"TRUE"
BODY_TYPE"PLUMBING"
CDS_LIB"mstr_standard";
"B \NAC \NWC"2;
"S \NAC"
BN"8"132;
%"TAP"
"6","(-5600,1850)","0","mstr_standard","I29";
;
HDL_TAP"TRUE"
BODY_TYPE"PLUMBING"
CDS_LIB"mstr_standard";
"B \NAC \NWC"2;
"S \NAC"
BN"7"133;
%"TAP"
"6","(-5600,1950)","0","mstr_standard","I31";
;
HDL_TAP"TRUE"
BODY_TYPE"PLUMBING"
CDS_LIB"mstr_standard";
"B \NAC \NWC"2;
"S \NAC"
BN"9"131;
%"TAP"
"6","(-5600,2000)","0","mstr_standard","I32";
;
HDL_TAP"TRUE"
BODY_TYPE"PLUMBING"
CDS_LIB"mstr_standard";
"B \NAC \NWC"2;
"S \NAC"
BN"10"130;
%"TAP"
"6","(-5600,2050)","0","mstr_standard","I33";
;
HDL_TAP"TRUE"
BODY_TYPE"PLUMBING"
CDS_LIB"mstr_standard";
"B \NAC \NWC"2;
"S \NAC"
BN"11"121;
%"TAP"
"6","(-5600,2100)","0","mstr_standard","I34";
;
HDL_TAP"TRUE"
BODY_TYPE"PLUMBING"
CDS_LIB"mstr_standard";
"B \NAC \NWC"2;
"S \NAC"
BN"12"120;
%"TAP"
"6","(-5600,2150)","0","mstr_standard","I35";
;
HDL_TAP"TRUE"
BODY_TYPE"PLUMBING"
CDS_LIB"mstr_standard";
"B \NAC \NWC"2;
"S \NAC"
BN"13"119;
%"TAP"
"6","(-5600,2200)","0","mstr_standard","I36";
;
HDL_TAP"TRUE"
BODY_TYPE"PLUMBING"
CDS_LIB"mstr_standard";
"B \NAC \NWC"2;
"S \NAC"
BN"14"118;
%"TAP"
"6","(-5600,2250)","0","mstr_standard","I37";
;
HDL_TAP"TRUE"
BODY_TYPE"PLUMBING"
CDS_LIB"mstr_standard";
"B \NAC \NWC"2;
"S \NAC"
BN"15"117;
%"TAP"
"6","(-5600,2300)","0","mstr_standard","I38";
;
HDL_TAP"TRUE"
BODY_TYPE"PLUMBING"
CDS_LIB"mstr_standard";
"B \NAC \NWC"2;
"S \NAC"
BN"16"116;
%"TAP"
"6","(-5600,2350)","0","mstr_standard","I39";
;
HDL_TAP"TRUE"
BODY_TYPE"PLUMBING"
CDS_LIB"mstr_standard";
"B \NAC \NWC"2;
"S \NAC"
BN"17"115;
%"TAP"
"6","(-5600,2400)","0","mstr_standard","I40";
;
HDL_TAP"TRUE"
BODY_TYPE"PLUMBING"
CDS_LIB"mstr_standard";
"B \NAC \NWC"2;
"S \NAC"
BN"18"114;
%"TAP"
"6","(-5600,2450)","0","mstr_standard","I41";
;
HDL_TAP"TRUE"
BODY_TYPE"PLUMBING"
CDS_LIB"mstr_standard";
"B \NAC \NWC"2;
"S \NAC"
BN"19"113;
%"TAP"
"6","(-5600,2500)","0","mstr_standard","I42";
;
HDL_TAP"TRUE"
BODY_TYPE"PLUMBING"
CDS_LIB"mstr_standard";
"B \NAC \NWC"2;
"S \NAC"
BN"20"112;
%"TAP"
"6","(-5600,2550)","0","mstr_standard","I43";
;
HDL_TAP"TRUE"
BODY_TYPE"PLUMBING"
CDS_LIB"mstr_standard";
"B \NAC \NWC"2;
"S \NAC"
BN"21"111;
%"TAP"
"6","(-5600,2600)","0","mstr_standard","I44";
;
HDL_TAP"TRUE"
BODY_TYPE"PLUMBING"
CDS_LIB"mstr_standard";
"B \NAC \NWC"2;
"S \NAC"
BN"22"110;
%"TAP"
"6","(-5600,2650)","0","mstr_standard","I45";
;
HDL_TAP"TRUE"
BODY_TYPE"PLUMBING"
CDS_LIB"mstr_standard";
"B \NAC \NWC"2;
"S \NAC"
BN"23"109;
%"TAP"
"6","(-5600,2700)","0","mstr_standard","I46";
;
HDL_TAP"TRUE"
BODY_TYPE"PLUMBING"
CDS_LIB"mstr_standard";
"B \NAC \NWC"2;
"S \NAC"
BN"24"108;
%"TAP"
"6","(-5600,2800)","0","mstr_standard","I47";
;
HDL_TAP"TRUE"
BODY_TYPE"PLUMBING"
CDS_LIB"mstr_standard";
"B \NAC \NWC"2;
"S \NAC"
BN"26"106;
%"TAP"
"6","(-5600,2750)","0","mstr_standard","I48";
;
HDL_TAP"TRUE"
BODY_TYPE"PLUMBING"
CDS_LIB"mstr_standard";
"B \NAC \NWC"2;
"S \NAC"
BN"25"107;
%"TAP"
"6","(-5600,2850)","0","mstr_standard","I49";
;
HDL_TAP"TRUE"
BODY_TYPE"PLUMBING"
CDS_LIB"mstr_standard";
"B \NAC \NWC"2;
"S \NAC"
BN"27"105;
%"TAP"
"6","(-5600,600)","0","mstr_standard","I5";
;
HDL_TAP"TRUE"
BODY_TYPE"PLUMBING"
CDS_LIB"mstr_standard";
"B \NAC \NWC"7;
"S \NAC"
BN"0"125;
%"TAP"
"6","(-5600,2900)","0","mstr_standard","I50";
;
HDL_TAP"TRUE"
BODY_TYPE"PLUMBING"
CDS_LIB"mstr_standard";
"B \NAC \NWC"2;
"S \NAC"
BN"28"104;
%"TAP"
"6","(-5600,2950)","0","mstr_standard","I51";
;
HDL_TAP"TRUE"
BODY_TYPE"PLUMBING"
CDS_LIB"mstr_standard";
"B \NAC \NWC"2;
"S \NAC"
BN"29"103;
%"TAP"
"6","(-5600,3050)","0","mstr_standard","I52";
;
HDL_TAP"TRUE"
BODY_TYPE"PLUMBING"
CDS_LIB"mstr_standard";
"B \NAC \NWC"2;
"S \NAC"
BN"31"101;
%"TAP"
"6","(-5600,3000)","0","mstr_standard","I53";
;
HDL_TAP"TRUE"
BODY_TYPE"PLUMBING"
CDS_LIB"mstr_standard";
"B \NAC \NWC"2;
"S \NAC"
BN"30"102;
%"TAP"
"6","(-5600,3100)","0","mstr_standard","I54";
;
HDL_TAP"TRUE"
BODY_TYPE"PLUMBING"
CDS_LIB"mstr_standard";
"B \NAC \NWC"2;
"S \NAC"
BN"32"100;
%"TAP"
"6","(-5600,3150)","0","mstr_standard","I55";
;
HDL_TAP"TRUE"
BODY_TYPE"PLUMBING"
CDS_LIB"mstr_standard";
"B \NAC \NWC"2;
"S \NAC"
BN"33"99;
%"TAP"
"6","(-5600,3200)","0","mstr_standard","I56";
;
HDL_TAP"TRUE"
BODY_TYPE"PLUMBING"
CDS_LIB"mstr_standard";
"B \NAC \NWC"2;
"S \NAC"
BN"34"98;
%"TAP"
"6","(-5600,3300)","0","mstr_standard","I57";
;
HDL_TAP"TRUE"
BODY_TYPE"PLUMBING"
CDS_LIB"mstr_standard";
"B \NAC \NWC"2;
"S \NAC"
BN"36"97;
%"TAP"
"6","(-5600,3250)","0","mstr_standard","I58";
;
HDL_TAP"TRUE"
BODY_TYPE"PLUMBING"
CDS_LIB"mstr_standard";
"B \NAC \NWC"2;
"S \NAC"
BN"35"17;
%"TAP"
"6","(-5600,3350)","0","mstr_standard","I59";
;
HDL_TAP"TRUE"
BODY_TYPE"PLUMBING"
CDS_LIB"mstr_standard";
"B \NAC \NWC"2;
"S \NAC"
BN"37"96;
%"TAP"
"6","(-5600,650)","0","mstr_standard","I6";
;
HDL_TAP"TRUE"
BODY_TYPE"PLUMBING"
CDS_LIB"mstr_standard";
"B \NAC \NWC"7;
"S \NAC"
BN"1"124;
%"TAP"
"6","(-5600,3400)","0","mstr_standard","I60";
;
HDL_TAP"TRUE"
BODY_TYPE"PLUMBING"
CDS_LIB"mstr_standard";
"B \NAC \NWC"2;
"S \NAC"
BN"38"18;
%"TAP"
"6","(-5600,3450)","0","mstr_standard","I61";
;
HDL_TAP"TRUE"
BODY_TYPE"PLUMBING"
CDS_LIB"mstr_standard";
"B \NAC \NWC"2;
"S \NAC"
BN"39"95;
%"TAP"
"6","(-5600,3500)","0","mstr_standard","I62";
;
HDL_TAP"TRUE"
BODY_TYPE"PLUMBING"
CDS_LIB"mstr_standard";
"B \NAC \NWC"2;
"S \NAC"
BN"40"94;
%"TAP"
"6","(-5600,3550)","0","mstr_standard","I63";
;
HDL_TAP"TRUE"
BODY_TYPE"PLUMBING"
CDS_LIB"mstr_standard";
"B \NAC \NWC"2;
"S \NAC"
BN"41"14;
%"TAP"
"6","(-5600,3600)","0","mstr_standard","I64";
;
HDL_TAP"TRUE"
BODY_TYPE"PLUMBING"
CDS_LIB"mstr_standard";
"B \NAC \NWC"2;
"S \NAC"
BN"42"93;
%"TAP"
"6","(-5600,3650)","0","mstr_standard","I65";
;
HDL_TAP"TRUE"
BODY_TYPE"PLUMBING"
CDS_LIB"mstr_standard";
"B \NAC \NWC"2;
"S \NAC"
BN"43"92;
%"TAP"
"6","(-5600,3700)","0","mstr_standard","I66";
;
HDL_TAP"TRUE"
BODY_TYPE"PLUMBING"
CDS_LIB"mstr_standard";
"B \NAC \NWC"2;
"S \NAC"
BN"44"91;
%"TAP"
"6","(-5600,3750)","0","mstr_standard","I67";
;
HDL_TAP"TRUE"
BODY_TYPE"PLUMBING"
CDS_LIB"mstr_standard";
"B \NAC \NWC"2;
"S \NAC"
BN"45"90;
%"TAP"
"6","(-5600,3800)","0","mstr_standard","I68";
;
HDL_TAP"TRUE"
BODY_TYPE"PLUMBING"
CDS_LIB"mstr_standard";
"B \NAC \NWC"2;
"S \NAC"
BN"46"89;
%"TAP"
"6","(-5600,3850)","0","mstr_standard","I69";
;
HDL_TAP"TRUE"
BODY_TYPE"PLUMBING"
CDS_LIB"mstr_standard";
"B \NAC \NWC"2;
"S \NAC"
BN"47"88;
%"TAP"
"6","(-5600,750)","0","mstr_standard","I7";
;
HDL_TAP"TRUE"
BODY_TYPE"PLUMBING"
CDS_LIB"mstr_standard";
"B \NAC \NWC"7;
"S \NAC"
BN"3"122;
%"TAP"
"6","(-5600,3900)","0","mstr_standard","I70";
;
HDL_TAP"TRUE"
BODY_TYPE"PLUMBING"
CDS_LIB"mstr_standard";
"B \NAC \NWC"2;
"S \NAC"
BN"48"87;
%"TAP"
"6","(-5600,3950)","0","mstr_standard","I71";
;
HDL_TAP"TRUE"
BODY_TYPE"PLUMBING"
CDS_LIB"mstr_standard";
"B \NAC \NWC"2;
"S \NAC"
BN"49"86;
%"TAP"
"6","(-5600,4000)","0","mstr_standard","I73";
;
HDL_TAP"TRUE"
BODY_TYPE"PLUMBING"
CDS_LIB"mstr_standard";
"B \NAC \NWC"2;
"S \NAC"
BN"50"85;
%"TAP"
"6","(-5600,4050)","0","mstr_standard","I74";
;
HDL_TAP"TRUE"
BODY_TYPE"PLUMBING"
CDS_LIB"mstr_standard";
"B \NAC \NWC"2;
"S \NAC"
BN"51"84;
%"TAP"
"6","(-5600,4100)","0","mstr_standard","I75";
;
HDL_TAP"TRUE"
BODY_TYPE"PLUMBING"
CDS_LIB"mstr_standard";
"B \NAC \NWC"2;
"S \NAC"
BN"52"83;
%"TAP"
"6","(-5600,4150)","0","mstr_standard","I76";
;
HDL_TAP"TRUE"
BODY_TYPE"PLUMBING"
CDS_LIB"mstr_standard";
"B \NAC \NWC"2;
"S \NAC"
BN"53"15;
%"TAP"
"6","(-5600,4200)","0","mstr_standard","I77";
;
HDL_TAP"TRUE"
BODY_TYPE"PLUMBING"
CDS_LIB"mstr_standard";
"B \NAC \NWC"2;
"S \NAC"
BN"54"82;
%"TAP"
"6","(-5600,4250)","0","mstr_standard","I78";
;
HDL_TAP"TRUE"
BODY_TYPE"PLUMBING"
CDS_LIB"mstr_standard";
"B \NAC \NWC"2;
"S \NAC"
BN"55"13;
%"TAP"
"6","(-5600,4300)","0","mstr_standard","I79";
;
HDL_TAP"TRUE"
BODY_TYPE"PLUMBING"
CDS_LIB"mstr_standard";
"B \NAC \NWC"2;
"S \NAC"
BN"56"81;
%"TAP"
"6","(-5600,700)","0","mstr_standard","I8";
;
HDL_TAP"TRUE"
BODY_TYPE"PLUMBING"
CDS_LIB"mstr_standard";
"B \NAC \NWC"7;
"S \NAC"
BN"2"123;
%"TAP"
"6","(-5600,4350)","0","mstr_standard","I80";
;
HDL_TAP"TRUE"
BODY_TYPE"PLUMBING"
CDS_LIB"mstr_standard";
"B \NAC \NWC"2;
"S \NAC"
BN"57"80;
%"TAP"
"6","(-5600,4400)","0","mstr_standard","I81";
;
HDL_TAP"TRUE"
BODY_TYPE"PLUMBING"
CDS_LIB"mstr_standard";
"B \NAC \NWC"2;
"S \NAC"
BN"58"79;
%"TAP"
"6","(-5600,4450)","0","mstr_standard","I82";
;
HDL_TAP"TRUE"
BODY_TYPE"PLUMBING"
CDS_LIB"mstr_standard";
"B \NAC \NWC"2;
"S \NAC"
BN"59"78;
%"TAP"
"6","(-5600,4500)","0","mstr_standard","I83";
;
HDL_TAP"TRUE"
BODY_TYPE"PLUMBING"
CDS_LIB"mstr_standard";
"B \NAC \NWC"2;
"S \NAC"
BN"60"77;
%"TAP"
"6","(-5600,4550)","0","mstr_standard","I84";
;
HDL_TAP"TRUE"
BODY_TYPE"PLUMBING"
CDS_LIB"mstr_standard";
"B \NAC \NWC"2;
"S \NAC"
BN"61"76;
%"TAP"
"6","(-5600,4600)","0","mstr_standard","I85";
;
HDL_TAP"TRUE"
BODY_TYPE"PLUMBING"
CDS_LIB"mstr_standard";
"B \NAC \NWC"2;
"S \NAC"
BN"62"75;
%"TAP"
"6","(-5600,4650)","0","mstr_standard","I86";
;
HDL_TAP"TRUE"
BODY_TYPE"PLUMBING"
CDS_LIB"mstr_standard";
"B \NAC \NWC"2;
"S \NAC"
BN"63"74;
%"TAP"
"6","(-2875,750)","2","mstr_standard","I87";
;
HDL_TAP"TRUE"
BODY_TYPE"PLUMBING"
CDS_LIB"mstr_standard";
"B \NAC \NWC"12;
"S \NAC"
BN"1"52;
%"TAP"
"6","(-2875,700)","2","mstr_standard","I88";
;
HDL_TAP"TRUE"
BODY_TYPE"PLUMBING"
CDS_LIB"mstr_standard";
"B \NAC \NWC"12;
"S \NAC"
BN"0"53;
%"TAP"
"6","(-2875,800)","2","mstr_standard","I89";
;
HDL_TAP"TRUE"
BODY_TYPE"PLUMBING"
CDS_LIB"mstr_standard";
"B \NAC \NWC"11;
"S \NAC"
BN"0"55;
%"TAP"
"6","(-5600,850)","0","mstr_standard","I9";
;
HDL_TAP"TRUE"
BODY_TYPE"PLUMBING"
CDS_LIB"mstr_standard";
"B \NAC \NWC"6;
"S \NAC"
BN"1"128;
%"TAP"
"6","(-2875,850)","2","mstr_standard","I90";
;
HDL_TAP"TRUE"
BODY_TYPE"PLUMBING"
CDS_LIB"mstr_standard";
"B \NAC \NWC"11;
"S \NAC"
BN"1"54;
%"TAP"
"6","(-2875,1050)","2","mstr_standard","I91";
;
HDL_TAP"TRUE"
BODY_TYPE"PLUMBING"
CDS_LIB"mstr_standard";
"B \NAC \NWC"9;
"S \NAC"
BN"2"65;
%"TAP"
"6","(-2875,1000)","2","mstr_standard","I92";
;
HDL_TAP"TRUE"
BODY_TYPE"PLUMBING"
CDS_LIB"mstr_standard";
"B \NAC \NWC"9;
"S \NAC"
BN"1"66;
%"TAP"
"6","(-2875,950)","2","mstr_standard","I93";
;
HDL_TAP"TRUE"
BODY_TYPE"PLUMBING"
CDS_LIB"mstr_standard";
"B \NAC \NWC"9;
"S \NAC"
BN"0"67;
%"TAP"
"6","(-2875,1150)","2","mstr_standard","I94";
;
HDL_TAP"TRUE"
BODY_TYPE"PLUMBING"
CDS_LIB"mstr_standard";
"B \NAC \NWC"9;
"S \NAC"
BN"4"63;
%"TAP"
"6","(-2875,1100)","2","mstr_standard","I95";
;
HDL_TAP"TRUE"
BODY_TYPE"PLUMBING"
CDS_LIB"mstr_standard";
"B \NAC \NWC"9;
"S \NAC"
BN"3"64;
%"TAP"
"6","(-2875,1200)","2","mstr_standard","I96";
;
HDL_TAP"TRUE"
BODY_TYPE"PLUMBING"
CDS_LIB"mstr_standard";
"B \NAC \NWC"9;
"S \NAC"
BN"5"62;
%"TAP"
"6","(-2875,1250)","2","mstr_standard","I97";
;
HDL_TAP"TRUE"
BODY_TYPE"PLUMBING"
CDS_LIB"mstr_standard";
"B \NAC \NWC"9;
"S \NAC"
BN"6"61;
%"TAP"
"6","(-2875,1300)","2","mstr_standard","I98";
;
HDL_TAP"TRUE"
BODY_TYPE"PLUMBING"
CDS_LIB"mstr_standard";
"B \NAC \NWC"9;
"S \NAC"
BN"7"60;
%"TAP"
"6","(-2875,1400)","2","mstr_standard","I99";
;
HDL_TAP"TRUE"
BODY_TYPE"PLUMBING"
CDS_LIB"mstr_standard";
"B \NAC \NWC"8;
"S \NAC"
BN"0"73;
END.
